# S9S_MB_2U (Grand Teton) — schematic parts with pin connectivity, parts 5748–5875 of 6093; source: Cadence DE-HDL packaged netlist (pstxprt.dat, pstxnet.dat, pstchip.dat)

R4689  Q_RES  33.2 1% EMPTY  pkg 0402LF  page 251 : 1 = SMB_LM75_0_3V3AUX_SCL ; 2 = SMB_HSC_TYPE_ADC_SCL
R4690  Q_RES  33.2 1% EMPTY  pkg 0402LF  page 251 : 1 = SMB_LM75_0_3V3AUX_SDA ; 2 = SMB_HSC_TYPE_ADC_SDA
R4691  Q_RES  0 5% EMPTY  pkg 0402LF  page 251 : 1 = HSC_TYPE_ADC_A0 ; 2 = SMB_HSC_TYPE_ADC_SDA
R4692  Q_RES  4.7K 1% EMPTY  pkg 0402LF  page 251 : 1 = P3V3_AUX ; 2 = TP_HSC_TYPE_ADC_ALERT
R4693  Q_RES  0 5% EMPTY  pkg 0402LF  page 306 : 1 = HSC_CSOUT ; 2 = HSC_D_OC
R4694  Q_RES  1K 1% CHIP  pkg 0402LF  page 167 : 1 = FM_P2E_BUF2_EQB1 ; 2 = GND
R4695  Q_RES  0 5% CHIP  pkg 0402LF  page 305 : 1 = SMB_SML1_PMBUS_HSC_SCL ; 2 = SMB_SML1_PMBUS_HSC_MODULE_SCL
R4696  Q_RES  0 5% CHIP  pkg 0402LF  page 305 : 1 = SMB_SML1_PMBUS_HSC_SDA ; 2 = SMB_SML1_PMBUS_HSC_MODULE_SDA
R4697  Q_RES  0 5% CHIP  pkg 0402LF  page 213 : 1 = RST_SRST_PLD_BMC_R_N ; 2 = RST_SRST_PLD_BMC_N
R4701  Q_RES  4.7K 5% CHIP  pkg 0402LF  page 245 : 1 = P3V3_AUX ; 2 = FM_FAN_PWR_EN
R4702  Q_RES  560 1% CHIP  pkg 0402LF  page 255 : 1 = LED_P12V_AUX_R1 ; 2 = LED_P12V_AUX_R2
R4703  Q_RES  560 1% CHIP  pkg 0402LF  page 255 : 1 = LED_P12V_PSU_R1 ; 2 = LED_P12V_PSU_R2
R4704  Q_RES  560 1% CHIP  pkg 0402LF  page 255 : 1 = LED_P12V_AUX_R2 ; 2 = LED_P12V_AUX_R3
R4705  Q_RES  560 1% CHIP  pkg 0402LF  page 255 : 1 = LED_P12V_PSU_R2 ; 2 = LED_P12V_PSU_R3
R4706  Q_RES  560 1% CHIP  pkg 0402LF  page 255 : 1 = LED_P12V_AUX_R3 ; 2 = P12V_AUX
R4707  Q_RES  560 1% CHIP  pkg 0402LF  page 255 : 1 = LED_P12V_PSU_R3 ; 2 = P12V_PSU
R4708  Q_RES  0 5% EMPTY  pkg 0402LF  page 242 : 1 = P12V_SCM_FAULT_N ; 2 = P12V_SCM_FAULT_R_N
R4709  Q_RES  0 5% CHIP  pkg 0402LF  page 242 : 1 = P12V_SCM_FLTB_N ; 2 = P12V_SCM_FAULT_R_N
R4710  Q_RES  4.7K 5% CHIP  pkg 0402LF  page 255 : 1 = P3V3_AUX ; 2 = LED_P12V_SCM_FAULT_D1
R4711  Q_RES  249 1% CHIP  pkg 0402LF  page 255 : 1 = LED_P12V_SCM_FAULT ; 2 = P3V3_AUX
R4712  Q_RES  100K 1% CHIP  pkg 0402LF  page 185 : 1 = RST_PFR_OVR_RTC ; 2 = GND
R4713  Q_RES  100K 1% CHIP  pkg 0402LF  page 185 : 1 = RST_PFR_OVR_SRTC ; 2 = GND
R4714  Q_RES  33.2 1% CHIP  pkg 0402LF  page 213 : 1 = SMB_HOST_3V3AUX_SDA_R4 ; 2 = SMB_HOST_3V3AUX_PLD_SDA
R4715  Q_RES  33.2 1% CHIP  pkg 0402LF  page 213 : 1 = SMB_HOST_3V3AUX_SCL_R4 ; 2 = SMB_HOST_3V3AUX_PLD_SCL
R4716  Q_RES  8.45K 1% EMPTY  pkg 0402LF  page 224 : 1 = P3V3_AUX ; 2 = FM_AC_PWR_BTN_R_N
R4717  Q_RES  0 5% EMPTY  pkg 0402LF  page 224 : 1 = FM_AC_PWR_BTN_R_N ; 2 = FM_AC_PWR_BTN_PLD_N
R4718  Q_RES  33.2 1% EMPTY  pkg 0402LF  page 224 : 1 = FM_AC_PWR_BTN_PLD_ISO_R_N ; 2 = FM_AC_PWR_BTN_PLD_ISO_N
R4719  Q_RES  10K 1% CHIP  pkg 0402LF  page 224 : 1 = P3V3_AUX ; 2 = FM_AC_PWR_BTN_PLD_ISO_N
R4720  Q_RES  0 5% CHIP  pkg 0402LF  page 240 : 1 = FM_AC_PWR_BTN_N ; 2 = FM_AC_PWR_BTN_R_N
R4721  Q_RES  0 5% CHIP  pkg 0402LF  page 245 : 1 = FM_AC_PWR_BTN_R_N ; 2 = FM_AC_PWR_BTN_PDB_N
R4722  Q_RES  10K 1% CHIP  pkg 0402LF  page 184 : 1 = FM_PCH_BMC_RST_R_N ; 2 = P3V3_AUX
R4723  Q_RES  33.2 1% CHIP  pkg 0402LF  page 215 : 1 = FM_PCH_BMC_RST_R_N ; 2 = FM_PCH_BMC_RST_N
R4724  Q_RES  100K 1% EMPTY  pkg 0402LF  page 144 : 1 = PRSNT_SWB_N ; 2 = GND
R4725  Q_RES  4.7K 5% CHIP  pkg 0402LF  page 144 : 1 = P3V3_AUX ; 2 = PRSNT_SWB
R4726  Q_RES  4.7K 5% CHIP  pkg 0402LF  page 144 : 1 = P3V3_AUX ; 2 = PRSNT_SWB_ISO_N
R4727  Q_RES  10K 1% CHIP  pkg 0402LF  page 144 : 1 = P3V3_AUX ; 2 = PRSNT_SWB_N
R4728  Q_RES  0 5% CHIP  pkg 0402LF  page 227 : 1 = PRSNT_SWB_ISO_N ; 2 = PRSNT_SWB_ISO_R1_N
R4729  Q_RES  0 5% CHIP  pkg 0402LF  page 227 : 1 = GPU_PRSNT_N_ISO ; 2 = GPU_PRSNT_N_ISO_R1
R4730  Q_RES  10K 1% CHIP  pkg 0402LF  page 144 : 1 = P3V3_AUX ; 2 = PRSNT_CABLE_SWB_B2_N
R4731  Q_RES  100K 1% EMPTY  pkg 0402LF  page 144 : 1 = PRSNT_CABLE_SWB_B2_N ; 2 = GND
R4732  Q_RES  4.7K 5% CHIP  pkg 0402LF  page 144 : 1 = P3V3_AUX ; 2 = PRSNT_CABLE_SWB_B2
R4733  Q_RES  4.7K 5% CHIP  pkg 0402LF  page 144 : 1 = P3V3_AUX ; 2 = PRSNT_CABLE_SWB_B2_ISO_N
R4734  Q_RES  0 5% CHIP  pkg 0402LF  page 227 : 1 = PRSNT_CABLE_GPU_B3_ISO_N ; 2 = PRSNT_CABLE_GPU_B3_ISO_R1_N
R4735  Q_RES  0 5% CHIP  pkg 0402LF  page 227 : 1 = PRSNT_CABLE_SWB_B2_ISO_N ; 2 = PRSNT_CABLE_SWB_B2_ISO_R_N
R4736  Q_RES  0 5% CHIP  pkg 0402LF  page 227 : 1 = PRSNT_CABLE_GPU_A2_ISO_N ; 2 = PRSNT_CABLE_GPU_A2_ISO_R1_N
R4737  Q_RES  10K 1% CHIP  pkg 0402LF  page 144 : 1 = P3V3_AUX ; 2 = PRSNT_CABLE_SWB_B1_N
R4738  Q_RES  100K 1% EMPTY  pkg 0402LF  page 144 : 1 = PRSNT_CABLE_SWB_B1_N ; 2 = GND
R4739  Q_RES  4.7K 5% CHIP  pkg 0402LF  page 144 : 1 = P3V3_AUX ; 2 = PRSNT_CABLE_SWB_B1
R4740  Q_RES  4.7K 5% CHIP  pkg 0402LF  page 144 : 1 = P3V3_AUX ; 2 = PRSNT_CABLE_SWB_B1_ISO_N
R4741  Q_RES  0 5% CHIP  pkg 0402LF  page 227 : 1 = PRSNT_CABLE_SWB_B1_ISO_N ; 2 = PRSNT_CABLE_SWB_B1_ISO_R_N
R4742  Q_RES  0 5% CHIP  pkg 0402LF  page 227 : 1 = PRSNT_CABLE_GPU_A1_ISO_N ; 2 = PRSNT_CABLE_GPU_A1_ISO_R1_N
R4745  Q_RES  10K 1% CHIP  pkg 0402LF  page 158 : 1 = P3V3_AUX ; 2 = OCP_SFF_AUX_PWR_PLD_EN_R
R4746  Q_RES  33.2 1% CHIP  pkg 0402LF  page 158 : 1 = HP_LVC3_OCP_V3_1_PWRGD_R ; 2 = HP_LVC3_OCP_V3_1_PWRGD_R2
R4747  Q_RES  33.2 1% CHIP  pkg 0402LF  page 158 : 1 = OCP_SFF_AUX_PWR_PLD_EN ; 2 = OCP_SFF_AUX_PWR_PLD_EN_R
R4748  Q_RES  0 5% EMPTY  pkg 0402LF  page 158 : 1 = HP_LVC3_OCP_V3_1_PWRGD_R2 ; 2 = OCP_SFF_AUX_PWR_EN_R2
R4749  Q_RES  0 5% EMPTY  pkg 0402LF  page 158 : 1 = OCP_SFF_AUX_PWR_PLD_EN_R ; 2 = OCP_SFF_AUX_PWR_EN_R2
R4750  Q_RES  49.9 1% CHIP  pkg 0402LF  page 158 : 1 = OCP_SFF_AUX_PWR_EN_R2 ; 2 = OCP_SFF_AUX_PWR_EN
R4751  Q_RES  33.2 1% CHIP  pkg 0402LF  page 216 : 1 = HP_LVC3_OCP_V3_1_PWRGD_R ; 2 = HP_LVC3_OCP_V3_1_FUSE_PWRGD
R4752  Q_RES  0 5% CHIP  pkg 0402LF  page 156 : 1 = HP_LVC3_OCP_V3_1_PRSNT2_N_R ; 2 = HP_LVC3_OCP_V3_1_PRSNT2_PLD_N
R4753  Q_RES  0 5% CHIP  pkg 0402LF  page 162 : 1 = HP_LVC3_OCP_V3_2_PRSNT2_N_R ; 2 = HP_LVC3_OCP_V3_2_PRSNT2_PLD_N
R4754  Q_RES  33.2 1% CHIP  pkg 0402LF  page 164 : 1 = HP_LVC3_OCP_V3_2_PWRGD_R ; 2 = HP_LVC3_OCP_V3_2_PWRGD_R2
R4755  Q_RES  33.2 1% CHIP  pkg 0402LF  page 164 : 1 = OCP_V3_2_AUX_PWR_PLD_EN ; 2 = OCP_V3_2_AUX_PWR_PLD_EN_R
R4756  Q_RES  10K 1% CHIP  pkg 0402LF  page 164 : 1 = P3V3_AUX ; 2 = OCP_V3_2_AUX_PWR_PLD_EN_R
R4757  Q_RES  0 5% EMPTY  pkg 0402LF  page 164 : 1 = HP_LVC3_OCP_V3_2_PWRGD_R2 ; 2 = OCP_V3_2_AUX_PWR_EN_R2
R4758  Q_RES  0 5% EMPTY  pkg 0402LF  page 164 : 1 = OCP_V3_2_AUX_PWR_PLD_EN_R ; 2 = OCP_V3_2_AUX_PWR_EN_R2
R4759  Q_RES  49.9 1% CHIP  pkg 0402LF  page 164 : 1 = OCP_V3_2_AUX_PWR_EN_R2 ; 2 = OCP_V3_2_AUX_PWR_EN
R4760  Q_RES  33.2 1% CHIP  pkg 0402LF  page 216 : 1 = HP_LVC3_OCP_V3_2_PWRGD_R ; 2 = HP_LVC3_OCP_V3_2_FUSE_PWRGD
R4761  Q_RES  10K 1% CHIP  pkg 0402LF  page 162 : 1 = P3V3_AUX ; 2 = HP_LVC3_OCP_V3_2_PRSNT2_PLD_N
R4762  Q_RES  10K 1% CHIP  pkg 0402LF  page 156 : 1 = P3V3_AUX ; 2 = HP_LVC3_OCP_V3_1_PRSNT2_PLD_N
R4763  Q_RES  10K 1% CHIP  pkg 0402LF  page 164 : 1 = P3V3_AUX ; 2 = HP_OCP_V3_2_EN
R4764  Q_RES  10K 1% CHIP  pkg 0402LF  page 158 : 1 = P3V3_AUX ; 2 = HP_OCP_V3_1_EN
R4765  Q_RES  33.2 1% CHIP  pkg 0402LF  page 216 : 1 = HP_LVC3_E1S_0_HSC_PWRGD ; 2 = HP_LVC3_E1S_0_HSC_PWRGD_PLD
R4766  Q_RES  49.9 1% CHIP  pkg 0402LF  page 183 : 1 = E1S_0_CLK_OE_N ; 2 = E1S_0_CLKREQ_N
R4767  Q_RES  49.9 1% CHIP  pkg 0402LF  page 191 : 1 = HP_E1S_0_P3V3_PWRGD ; 2 = HP_E1S_0_P3V3_PWRGD_PLD
R4768  Q_RES  10K 1% CHIP  pkg 0402LF  page 183 : 1 = E1S_0_CLK_OE_N ; 2 = P3V3_AUX
R4769  Q_RES  100K 1% CHIP  pkg 0402LF  page 245 : 1 = FM_PDB_BUF_EN_R ; 2 = GND
R4770  Q_RES  0 5% CHIP  pkg 0402LF  page 242 : 1 = HP_LVC3_SCM_HSC_PWRGD_R ; 2 = HP_LVC3_SCM_HSC_PWRGD
R4771  Q_RES  33.2 1% CHIP  pkg 0402LF  page 216 : 1 = HP_LVC3_SCM_HSC_PWRGD ; 2 = HP_LVC3_SCM_HSC_PWRGD_PLD
R4772  Q_RES  10K 1% EMPTY  pkg 0402LF  page 307 : 1 = P3V3_AUX ; 2 = UV_ADR_P2V5_COMP
R4773  Q_RES  10K 1% EMPTY  pkg 0402LF  page 307 : 1 = P3V3_AUX ; 2 = UV_P2V5_COMP
R4774  Q_RES  17.8K 1% EMPTY  pkg 0402LF  page 307 : 1 = P12V_AUX ; 2 = P12V_AUX_UV_ADR_TRIGGER
R4775  Q_RES  5.11K 1% EMPTY  pkg 0402LF  page 307 : 1 = P12V_AUX_UV_ADR_TRIGGER ; 2 = GND
R4776  Q_RES  17.8K 1% EMPTY  pkg 0402LF  page 307 : 1 = P12V_AUX ; 2 = P12V_AUX_UV_TRIGGER
R4777  Q_RES  5.11K 1% EMPTY  pkg 0402LF  page 307 : 1 = P12V_AUX_UV_TRIGGER ; 2 = GND
R4778  Q_RES  1M 1% CHIP  pkg 0402LF  page 307 : 1 = P12V_AUX_UV_ADR_TRIGGER ; 2 = FM_UV_ADR_TRIGGER_N_R2
R4779  Q_RES  1M 1% CHIP  pkg 0402LF  page 307 : 1 = P12V_AUX_UV_TRIGGER ; 2 = IRQ_UV_DETECT_R2_N
R4780  Q_RES  0 5% CHIP  pkg 0402LF  page 262 : 1 = PWRGD_P1V05_PCH_AUX_R ; 2 = PWRGD_PVNN_PCH_AUX
R4781  Q_RES  0 5% CHIP  pkg 0402LF  page 292 : 1 = PWRGD_PVCCINFAON_CPU1 ; 2 = PWRGD_PVCCINFAON_CPU1_R
R4782  Q_RES  33.2 1% EMPTY  pkg 0402LF  page 307 : 1 = FM_UV_ADR_TRIGGER_N_R2 ; 2 = FM_UV_ADR_TRIGGER_N
R4783  Q_RES  33.2 1% EMPTY  pkg 0402LF  page 307 : 1 = IRQ_UV_DETECT_R2_N ; 2 = IRQ_UV_DETECT_N
R4784  Q_RES  10K 1% EMPTY  pkg 0402LF  page 307 : 1 = P3V3_AUX ; 2 = FM_UV_ADR_TRIGGER_N
R4785  Q_RES  10K 1% EMPTY  pkg 0402LF  page 307 : 1 = P3V3_AUX ; 2 = IRQ_UV_DETECT_N
R4786  Q_RES  10K 1% EMPTY  pkg 0402LF  page 307 : 1 = P3V3_AUX ; 2 = DSW_PWROK_P2V5_COMP
R4787  Q_RES  1M 1% EMPTY  pkg 0402LF  page 307 : 1 = PWRGD_DSW_PWROK_TRIGGER ; 2 = PWRGD_DSW_PWROK_R5
R4788  Q_RES  33.2 1% EMPTY  pkg 0402LF  page 307 : 1 = PWRGD_DSW_PWROK_R5 ; 2 = PWRGD_DSW_PWROK
R4789  Q_RES  10K 1% EMPTY  pkg 0402LF  page 307 : 1 = P3V3_AUX ; 2 = PWRGD_DSW_PWROK
R4790  Q_RES  4.75K 1% EMPTY  pkg 0402LF  page 307 : 1 = P12V_AUX ; 2 = PWRGD_DSW_PWROK_TRIGGER
R4791  Q_RES  2K 1% EMPTY  pkg 0402LF  page 307 : 1 = PWRGD_DSW_PWROK_TRIGGER ; 2 = GND
R4792  Q_RES  10K 1% EMPTY  pkg 0402LF  page 306 : 1 = P3V3_AUX ; 2 = OC_P2V5_COMP
R4793  Q_RES  1M 1% EMPTY  pkg 0402LF  page 306 : 1 = HSC_OC_VOL ; 2 = HSC_D_OC_R2
R4794  Q_RES  33.2 1% EMPTY  pkg 0402LF  page 306 : 1 = HSC_D_OC_R2 ; 2 = A_HSC_LOW_GATE
R4795  Q_RES  160K 1% EMPTY  pkg 0402LF  page 306 : 1 = HSC_CSOUT ; 2 = HSC_OC_VOL
R4796  Q_RES  10K 1% EMPTY  pkg 0402LF  page 306 : 1 = HSC_OC_VOL ; 2 = GND
R4797  Q_RES  10K 1% EMPTY  pkg 0402LF  page 306 : 1 = P3V3_AUX ; 2 = A_HSC_LOW_GATE
R4798  Q_RES  10K 1% CHIP  pkg 0402LF  page 144 : 1 = P3V3_AUX ; 2 = PRSNT_CABLE_GPU_A3_N
R4799  Q_RES  100K 1% EMPTY  pkg 0402LF  page 144 : 1 = PRSNT_CABLE_GPU_A3_N ; 2 = GND
R4800  Q_RES  4.7K 5% CHIP  pkg 0402LF  page 144 : 1 = P3V3_AUX ; 2 = PRSNT_CABLE_GPU_A3
R4801  Q_RES  4.7K 5% CHIP  pkg 0402LF  page 144 : 1 = P3V3_AUX ; 2 = PRSNT_CABLE_GPU_A3_ISO_N
R4802  Q_RES  0 5% CHIP  pkg 0402LF  page 227 : 1 = PRSNT_CABLE_GPU_A3_ISO_N ; 2 = PRSNT_CABLE_GPU_A3_ISO_R_N
R4803  Q_RES  0 5% CHIP  pkg 0402LF  page 189 : 1 = P1V05_PCH_AUX ; 2 = P1V05_PCH_PLL_AUX
R4804  Q_RES  1K 1% EMPTY  pkg 0402LF  page 306 : 1 = P3V3_AUX ; 2 = U205_VDD
R4805  Q_RES  1K 1% EMPTY  pkg 0402LF  page 306 : 1 = P3V3_AUX ; 2 = U369_VDD
R4806  Q_RES  1K 1% CHIP  pkg 0402LF  page 306 : 1 = P12V_AUX ; 2 = U206_VDD
R4807  Q_RES  0 5% EMPTY  pkg 0402LF  page 244 : 1 = PWRGD_DSW_PWROK_R1 ; 2 = PWRGD_DSW_PWROK_R2
R4808  Q_RES  100K 1% EMPTY  pkg 0402LF  page 244 : 1 = PWRGD_DSW_PWROK ; 2 = GND
R4809  Q_RES  0 5% CHIP  pkg 0402LF  page 240 : 1 = FM_BMC_INTRUDER_N ; 2 = GND
R4892  Q_RES  49.9 1% EMPTY  pkg 0402LF  page 305 : 1 = P12V_HSC_TEMP_R ; 2 = P12V_HSC_TEMP_D+
R4893  Q_RES  49.9 1% EMPTY  pkg 0402LF  page 305 : 1 = P12V_HSC_TEMP_E ; 2 = P12V_HSC_TEMP_D-
R4894  Q_RES  0 5% EMPTY  pkg 0402LF  page 305 : 1 = P12V_HSC_TEMP_SCL ; 2 = SMB_LM75_0_3V3AUX_SCL
R4895  Q_RES  0 5% EMPTY  pkg 0402LF  page 305 : 1 = P12V_HSC_TEMP_SDA ; 2 = SMB_LM75_0_3V3AUX_SDA
R4896  Q_RES  0 5% EMPTY  pkg 0402LF  page 305 : 1 = P12V_HSC_T_CRIT_N ; 2 = P12V_HSC_T_CRIT_R_N
R4901  Q_RES  82K 1% CHIP  pkg 0402LF  page 301 : 1 = P12V_PSU_FUSE ; 2 = HSC_EN
R5234  Q_RES  0 5% CHIP  pkg 0402LF  page 152 : 1 = USB2_HUB_BUF_SWB_R_DP ; 2 = USB2_HUB_BUF_SWB_DP
R5236  Q_RES  0 5% CHIP  pkg 0402LF  page 152 : 1 = USB2_HUB_BUF_SWB_R_DN ; 2 = USB2_HUB_BUF_SWB_DN
R5238  Q_RES  3.9K 5% EMPTY  pkg 0402LF  page 152 : 1 = PD_U5201_EQ ; 2 = GND
R5377  Q_RES  0 5% CHIP  pkg 0402LF  page 190 : 1 = HDD_ACTIVITY_BUF_N ; 2 = PU_BUFFER_HDD_ACTIVITY
R5487  Q_RES  0 5% CHIP  pkg 0402LF  page 156 : 1 = HP_LVC3_OCP_V3_1_EN ; 2 = P3V3_OCP_EN_1_R

SW5  SW_PUSHBUTTON4P_24  SW4S_DTSM-61N-S-Q-T/R MECH  pkg SW4S_DTSM-61N  page 201
  1  \1\  BI  = PD_RST_RTCRST_N
  2  \2\  BI  = PD_RST_RTCRST_N
  3  \3\  BI  = RST_RTCRST_N
  4  \4\  BI  = RST_RTCRST_N
